%FSTAX25Y25*%
%MOIN*%
%SFA1B1*%

%IPPOS*%
%ADD10C,0.008000*%
%ADD14C,0.010000*%
%ADD18C,0.006000*%
%ADD22C,0.005000*%
%ADD147C,0.020000*%
%ADD148C,0.015000*%
%ADD155C,0.075000*%
%ADD162C,0.055000*%
%ADD165C,0.016000*%
%LNgrandmaster-1*%
%LPD*%
G54D10*
X0775984Y0581102D02*
X0785882Y0591D01*
X0738583Y0581102D02*
X0775984D01*
X0728685Y0591D02*
X0738583Y0581102D01*
X0785882Y0591D02*
X08443D01*
X06995D02*
X0728685D01*
X0949784Y0909284D02*
X1125716D01*
X09495Y0909D02*
X0949784Y0909284D01*
X0994828Y06516D02*
X0998Y0654772D01*
Y0654783*
X09985Y0655283*
Y06555*
X0988794Y06516D02*
X0994828D01*
X09954Y06556D02*
X0996D01*
X0994206Y0656794D02*
X09954Y06556D01*
X09921Y0656794D02*
X0994206D01*
X0781294Y0667794D02*
X0787266D01*
X0787372Y06679*
X0787184Y06814D02*
X0857828D01*
X0787009Y0681574D02*
X0787184Y06814D01*
X08321Y07219D02*
X11568D01*
X08685Y06485D02*
X0953394D01*
X0957494Y06444*
X09984*
X10055Y06515*
X08375Y06945D02*
X0932228D01*
X0934728Y0692*
X0955994*
X0957894Y06901*
X09738*
X09795Y06844*
X11041Y0827D02*
X12325D01*
X11036Y08265D02*
X11041Y0827D01*
X09735Y08265D02*
X11036D01*
X0849Y0724D02*
X11625D01*
X0861917Y06774D02*
X0862317Y0677D01*
X08617Y06774D02*
X0861917D01*
X0862317Y0677D02*
X09466D01*
X09484Y06788*
X0969406*
X0970006Y06794*
X0998386*
X0998987Y068*
X10055*
X1228683Y08119D02*
X1229284Y08125D01*
X12295*
X1000272Y08119D02*
X1228683D01*
X0999673Y08125D02*
X1000272Y08119D01*
X0993Y08125D02*
X0999673D01*
X0908728Y07974D02*
X09188D01*
X0906528Y07952D02*
X0908728Y07974D01*
X08589Y07952D02*
X0906528D01*
X08414Y08127D02*
X08589Y07952D01*
X1010495Y07665D02*
X1017067Y0759928D01*
X08485Y07665D02*
X1010495D01*
X1012306Y06755D02*
X10125D01*
X1010706Y06739D02*
X1012306Y06755D01*
X0957006Y06739D02*
X1010706D01*
X0956906Y06738D02*
X0957006Y06739D01*
X08595Y06738D02*
X0956906D01*
X0829Y0692D02*
X0932466D01*
X0934066Y06904*
X0943422*
X0944322Y06895*
X09545*
X08485Y077D02*
X085Y07685D01*
X1020306*
X1028878Y0759928*
X0857Y06794D02*
X0862528D01*
X0863628Y06783*
X09456*
X09477Y06804*
X0962602*
X0964202Y0682*
X09935*
X0825Y08265D02*
X0839574D01*
X0840133Y0827059*
X0868379*
X0868769Y082745*
X0935684*
X0935781Y0827547*
X0936347*
X09365Y08277*
X0857033Y07416D02*
X0857633Y0741D01*
X08566Y07416D02*
X0857033D01*
X0857633Y0741D02*
X1003D01*
X0949002Y0677D02*
X0971D01*
X0947402Y06754D02*
X0949002Y0677D01*
X0860728Y06754D02*
X0947402D01*
X0860228Y06759D02*
X0860728Y06754D01*
X0854Y06759D02*
X0860228D01*
X0857828Y06814D02*
X0858328Y06809D01*
X09268*
X1226824Y0823D02*
X1227257D01*
X1225924Y08239D02*
X1226824Y0823D01*
X09797Y08239D02*
X1225924D01*
X0745Y08151D02*
X07451Y08152D01*
X08429D02*
X08495Y08086D01*
X07451Y08152D02*
X08429D01*
X08414Y08561D02*
X08425Y0855D01*
X07431Y08561D02*
X08414D01*
X07587Y0914D02*
X0797652D01*
X07576Y09129D02*
X07587Y0914D01*
X0799252Y09156D02*
X0803D01*
X0797652Y0914D02*
X0799252Y09156D01*
X0777Y0916D02*
X0797814D01*
X0801364Y091955*
X0804636D02*
X0808186Y0916D01*
X0996025*
X1000039Y0911987*
X0801364Y091955D02*
X0804636D01*
X0805086Y09021D02*
X08235D01*
X0804636Y090165D02*
X0805086Y09021D01*
X0801364Y090165D02*
X0804636D01*
X0800914Y09021D02*
X0801364Y090165D01*
X07895Y09021D02*
X0800914D01*
X07894Y09022D02*
X07895Y09021D01*
X09595Y0761D02*
X09614Y07591D01*
X0956172Y0761D02*
X09595D01*
X0955672Y07605D02*
X0956172Y0761D01*
X08812Y07605D02*
X0955672D01*
X1233281Y0832298D02*
X1234491Y0833508D01*
X0953302Y0832298D02*
X1233281D01*
X09293Y08348D02*
X0960272D01*
X11046Y083D02*
X1242351D01*
X09644Y08297D02*
X11043D01*
X11046Y083*
X0962972Y08375D02*
X124D01*
X0960272Y08348D02*
X0962972Y08375D01*
X09448Y0844D02*
X1246D01*
X09427Y08461D02*
X09448Y0844D01*
X09436Y084D02*
X109125D01*
X09385Y08451D02*
X09436Y084D01*
X1246Y0844D02*
X1247Y0843D01*
X09791Y08204D02*
X1229857D01*
X094212Y06686D02*
X0958928D01*
X0941978Y0668459D02*
X094212Y06686D01*
X0919309Y06677D02*
X0920137Y0668528D01*
X0919471Y06697D02*
X0919599Y0669828D01*
X0958928Y06686D02*
X0959628Y06679D01*
X0940928Y0669759D02*
X094267Y06715D01*
X07884Y06697D02*
X0919471D01*
X0959628Y06679D02*
X09715D01*
X0787572Y06677D02*
X0919309D01*
X0787372Y06679D02*
X0787572Y06677D01*
X0919599Y0669828D02*
X0930229D01*
X0930299Y0669759*
X0940928*
X092976Y0668459D02*
X0941978D01*
X092969Y0668528D02*
X092976Y0668459D01*
X0920137Y0668528D02*
X092969D01*
X094267Y06715D02*
X0958D01*
X08658Y06645D02*
X0977292D01*
X0978292Y06655*
X090725Y06595D02*
X090815Y06604D01*
X0968948D02*
X0969548Y0661D01*
X090815Y06604D02*
X0968948D01*
X109175Y08405D02*
X1243057D01*
X1243557Y084D02*
X1243773D01*
X1243057Y08405D02*
X1243557Y084D01*
X08469Y05936D02*
Y05941D01*
X08443Y0591D02*
X08469Y05936D01*
X0871Y06595D02*
X090725D01*
X0891Y0654D02*
X0986394D01*
X0988794Y06516*
X1232384Y08159D02*
X1232784Y08155D01*
X1005072Y08159D02*
X1232384D01*
X1004672Y08155D02*
X1005072Y08159D01*
X1232784Y08155D02*
X1233D01*
X09845D02*
X1004672D01*
X0896476Y082615D02*
X0898726Y08239D01*
X0869308Y082615D02*
X0896476D01*
X08451Y08239D02*
X0867058D01*
X0898726D02*
X09221D01*
X0867058D02*
X0869308Y082615D01*
X0841Y08198D02*
X08451Y08239D01*
X0858317Y08292D02*
X0858817Y08297D01*
X08581Y08292D02*
X0858317D01*
X0858817Y08297D02*
X09243D01*
X08657Y06644D02*
X08658Y06645D01*
X07782Y06301D02*
X08196D01*
X08197Y06302*
X0844428Y08204D02*
X08582D01*
X0841828Y08178D02*
X0844428Y08204D01*
X0840172Y08178D02*
X0841828D01*
X0837572Y08204D02*
X0840172Y08178D01*
X08196Y08204D02*
X0837572D01*
X06999Y06434D02*
X0700069D01*
X08265Y0651D02*
X09535D01*
X0700769Y06441D02*
X08437D01*
X08019Y063656D02*
X080196Y06365D01*
X07995Y0634D02*
X0937D01*
X0700069Y06434D02*
X0700769Y06441D01*
X0805Y0639D02*
X0937D01*
X0939274Y06365D02*
X09395Y0636726D01*
X080196Y06365D02*
X0939274D01*
X0849Y06323D02*
X08493Y0632D01*
X0800628Y06323D02*
X0849D01*
X0800328Y0632D02*
X0800628Y06323D01*
X0784871Y0632D02*
X0800328D01*
X0766393Y06323D02*
X0767753Y063366D01*
X0783211*
X0784871Y0632*
X07556Y06323D02*
X0766393D01*
X08516Y07467D02*
X0858872D01*
X08914Y07485D02*
X08939Y0746D01*
X0860672Y07485D02*
X08914D01*
X0858872Y07467D02*
X0860672Y07485D01*
X08832Y07267D02*
X09333D01*
X08794Y07311D02*
X08828Y07345D01*
X09489*
X0841935Y07625D02*
X08949D01*
X07Y0696D02*
X07011Y06971D01*
X084*
X07178Y07318D02*
X084D01*
X07011Y07485D02*
X07178Y07318D01*
X08634Y0662D02*
X0945979D01*
X0854729Y0862D02*
X0879D01*
X0812006Y08591D02*
X0824796D01*
X0829077Y0863381*
X0853348*
X0854729Y0862*
X0811343Y08575D02*
X0860208D01*
X0862708Y086*
X07745Y08665D02*
X0774581Y0866581D01*
X0866919*
X0867Y08665*
X0754Y08625D02*
X0786106D01*
X0788587Y0864981*
X0864233*
X0810606Y08605D02*
X0812006Y08591D01*
X07584Y08581D02*
X0810743D01*
X0864233Y0864981D02*
X0865215Y0864D01*
X09415*
X07875Y08605D02*
X0810606D01*
X0810743Y08581D02*
X0811343Y08575D01*
X0862708Y086D02*
X0923D01*
X07565D02*
X07584Y08581D01*
X0851606Y0851D02*
X0856006Y08466D01*
X0902733D02*
X0904633Y08485D01*
X0952*
X0856006Y08466D02*
X0902733D01*
X08225Y0851D02*
X0851606D01*
X0898354Y08755D02*
X0969D01*
X0900969Y0884D02*
X0969D01*
X09005Y0883531D02*
X0900969Y0884D01*
X09005Y08835D02*
Y0883531D01*
X08885Y06565D02*
X09318D01*
X09327Y06556D02*
X0976D01*
X09318Y06565D02*
X09327Y06556D01*
X0976D02*
X09798Y06594D01*
X0989494D02*
X09921Y0656794D01*
X09798Y06594D02*
X0989494D01*
X0994956Y0660356D02*
X1016856D01*
X0994312Y0661D02*
X0994956Y0660356D01*
X0969548Y0661D02*
X0994312D01*
X09535Y0651D02*
X09585Y0646D01*
X09913*
X0993Y06477*
X09952D02*
X10025Y0655D01*
X0993Y06477D02*
X09952D01*
X1016856Y0660356D02*
X1017Y06605D01*
X0945979Y0662D02*
X0946735Y0662756D01*
X1014146*
X0978292Y06655D02*
X10125D01*
X0979Y08205D02*
X09791Y08204D01*
X1229857D02*
X1229957Y08203D01*
X1000039Y0911987D02*
X1074487D01*
X0982Y0818D02*
X12265D01*
X12266Y08179*
X1236795Y08195D02*
X1243D01*
X1235195Y08179D02*
X1236795Y08195D01*
X12266Y08179D02*
X1235195D01*
X1242351Y083D02*
X1242851Y08295D01*
X12435*
X109125Y084D02*
X109175Y08405D01*
X0946Y0846D02*
X125D01*
G54D14*
X08716Y08114D02*
Y08164D01*
Y08114D02*
X08782Y08048D01*
X08942*
X0904685Y0815285*
Y0815785D02*
X09048Y08159D01*
X0904685Y0815285D02*
Y0815785D01*
G54D18*
X08074Y064156D02*
X0807417Y0641543D01*
X0939727*
X0939744Y0641526*
G54D22*
X0862429Y0568829D02*
D01*
X0861952Y0568318*
X0861513Y0567776*
X0861113Y0567204*
X0860753Y0566606*
X0860437Y0565984*
X0860164Y0565341*
X0859937Y0564681*
X0859756Y0564007*
X0859623Y0563322*
X0859538Y0562629*
X0859501Y0561932*
X08595Y0561758*
X08676Y0574D02*
D01*
X0867892Y0574313*
X0868162Y0574647*
X0868408Y0574998*
X0868629Y0575366*
X0868824Y0575748*
X0868991Y0576143*
X0869131Y0576549*
X0869242Y0576963*
X0869324Y0577384*
X0869376Y057781*
X0869399Y0578238*
X08694Y0578346*
X085875Y05373D02*
D01*
X0858802Y0537301*
X0858854Y0537307*
X0858905Y0537316*
X0858956Y0537329*
X0859006Y0537345*
X0859055Y0537364*
X0859102Y0537387*
X0859147Y0537413*
X085919Y0537443*
X0859232Y0537475*
X085927Y053751*
X0859307Y0537548*
X0859341Y0537588*
X0859371Y053763*
X0859399Y0537675*
X0859424Y0537721*
X0859445Y0537769*
X0859463Y0537818*
X0859477Y0537868*
X0859488Y0537919*
X0859495Y0537971*
X0859499Y0538023*
X08595Y053805*
X0858162Y05373D02*
D01*
X0858109Y0537298*
X0858057Y0537292*
X0858006Y0537283*
X0857955Y053727*
X0857905Y0537254*
X0857856Y0537235*
X0857809Y0537212*
X0857764Y0537186*
X0857721Y0537156*
X0857679Y0537124*
X0857641Y0537089*
X0857604Y0537051*
X085757Y0537011*
X085754Y0536969*
X0857512Y0536925*
X0857487Y0536878*
X0857466Y053683*
X0857448Y0536781*
X0857434Y0536731*
X0857423Y053668*
X0857416Y0536628*
X0857412Y0536576*
Y0536523*
X0857416Y0536471*
X0857423Y0536419*
X0857434Y0536368*
X0857448Y0536318*
X0857466Y0536269*
X0857487Y0536221*
X0857512Y0536175*
X085754Y053613*
X085757Y0536088*
X0857604Y0536048*
X0857641Y053601*
X0857679Y0535975*
X0857721Y0535943*
X0857764Y0535913*
X0857809Y0535887*
X0857856Y0535864*
X0857905Y0535845*
X0857955Y0535829*
X0858006Y0535816*
X0858057Y0535807*
X0858109Y0535801*
X0858162Y05358*
X0859119Y05343D02*
D01*
X0859171Y0534301*
X0859223Y0534307*
X0859274Y0534316*
X0859325Y0534329*
X0859375Y0534345*
X0859424Y0534364*
X0859471Y0534387*
X0859516Y0534413*
X0859559Y0534443*
X0859601Y0534475*
X0859639Y053451*
X0859676Y0534548*
X085971Y0534588*
X085974Y053463*
X0859768Y0534675*
X0859793Y0534721*
X0859814Y0534769*
X0859832Y0534818*
X0859846Y0534868*
X0859857Y0534919*
X0859864Y0534971*
X0859868Y0535023*
Y0535076*
X0859864Y0535128*
X0859857Y053518*
X0859846Y0535231*
X0859832Y0535281*
X0859814Y053533*
X0859793Y0535378*
X0859768Y0535425*
X085974Y0535469*
X085971Y0535511*
X0859676Y0535551*
X0859639Y0535589*
X0859601Y0535624*
X0859559Y0535656*
X0859516Y0535686*
X0859471Y0535712*
X0859424Y0535735*
X0859375Y0535754*
X0859325Y053577*
X0859274Y0535783*
X0859223Y0535792*
X0859171Y0535798*
X0859119Y05358*
X0858062Y05343D02*
D01*
X0858009Y0534298*
X0857957Y0534292*
X0857906Y0534283*
X0857855Y053427*
X0857805Y0534254*
X0857756Y0534235*
X0857709Y0534212*
X0857664Y0534186*
X0857621Y0534156*
X0857579Y0534124*
X0857541Y0534089*
X0857504Y0534051*
X085747Y0534011*
X085744Y0533969*
X0857412Y0533925*
X0857387Y0533878*
X0857366Y053383*
X0857348Y0533781*
X0857334Y0533731*
X0857323Y053368*
X0857316Y0533628*
X0857312Y0533576*
Y0533523*
X0857316Y0533471*
X0857323Y0533419*
X0857334Y0533368*
X0857348Y0533318*
X0857366Y0533269*
X0857387Y0533221*
X0857412Y0533175*
X085744Y053313*
X085747Y0533088*
X0857504Y0533048*
X0857541Y053301*
X0857579Y0532975*
X0857621Y0532943*
X0857664Y0532913*
X0857709Y0532887*
X0857756Y0532864*
X0857805Y0532845*
X0857855Y0532829*
X0857906Y0532816*
X0857957Y0532807*
X0858009Y0532801*
X0858062Y05328*
X08595Y053205D02*
D01*
X0859498Y0532102*
X0859492Y0532154*
X0859483Y0532205*
X085947Y0532256*
X0859454Y0532306*
X0859435Y0532355*
X0859412Y0532402*
X0859386Y0532447*
X0859356Y053249*
X0859324Y0532532*
X0859289Y053257*
X0859251Y0532607*
X0859211Y0532641*
X0859169Y0532671*
X0859125Y0532699*
X0859078Y0532724*
X085903Y0532745*
X0858981Y0532763*
X0858931Y0532777*
X085888Y0532788*
X0858828Y0532795*
X0858776Y0532799*
X085875Y05328*
X08653Y0587258D02*
D01*
X0865275Y0587955*
X0865202Y0588649*
X0865081Y0589337*
X0864912Y0590014*
X0864696Y0590678*
X0864435Y0591325*
X0864129Y0591952*
X086378Y0592557*
X086339Y0593135*
X086296Y0593685*
X0862493Y0594204*
X0862371Y0594329*
X0890392Y0528306D02*
D01*
X0890423Y052818*
X0890464Y0528058*
X0890513Y0527938*
X089057Y0527822*
X0890635Y0527711*
X0890708Y0527604*
X0890788Y0527503*
X0890875Y0527407*
X0890968Y0527318*
X0891068Y0527236*
X0891173Y052716*
X0891283Y0527092*
X0891397Y0527032*
X0891515Y052698*
X0891637Y0526937*
X0891761Y0526902*
X0891888Y0526876*
X0892016Y0526858*
X0892144Y052685*
X0892274Y0526851*
X0892402Y052686*
X089253Y0526879*
X0892656Y0526906*
X089278Y0526943*
X0892901Y0526987*
X0893019Y0527041*
X0893133Y0527102*
X0893242Y0527171*
X0893346Y0527247*
X0893445Y0527331*
X0893537Y0527421*
X0893623Y0527517*
X0893702Y052762*
X0893756Y05277*
X0890392Y0528306D02*
D01*
X0890383Y0528339*
X0890372Y0528373*
X0890359Y0528405*
X0890343Y0528436*
X0890326Y0528466*
X0890306Y0528495*
X0890284Y0528523*
X0890261Y0528549*
X0890236Y0528573*
X0890209Y0528595*
X0890181Y0528615*
X0890151Y0528634*
X089012Y052865*
X0890088Y0528664*
X0890055Y0528676*
X0890022Y0528685*
X0889987Y0528693*
X0889953Y0528697*
X0889918Y05287*
X0889901Y05287*
X0874192Y0528606D02*
D01*
X0874223Y052848*
X0874264Y0528358*
X0874313Y0528238*
X087437Y0528122*
X0874435Y0528011*
X0874508Y0527904*
X0874588Y0527803*
X0874675Y0527707*
X0874768Y0527618*
X0874868Y0527536*
X0874973Y052746*
X0875083Y0527392*
X0875197Y0527332*
X0875315Y052728*
X0875437Y0527237*
X0875561Y0527202*
X0875688Y0527176*
X0875816Y0527158*
X0875944Y052715*
X0876074Y0527151*
X0876202Y052716*
X087633Y0527179*
X0876456Y0527206*
X087658Y0527243*
X0876701Y0527287*
X0876819Y0527341*
X0876933Y0527402*
X0877042Y0527471*
X0877146Y0527547*
X0877245Y0527631*
X0877337Y0527721*
X0877423Y0527817*
X0877502Y052792*
X0877561Y0528007*
X0874192Y0528606D02*
D01*
X0874183Y0528639*
X0874172Y0528673*
X0874159Y0528705*
X0874143Y0528736*
X0874126Y0528766*
X0874106Y0528795*
X0874084Y0528823*
X0874061Y0528849*
X0874036Y0528873*
X0874009Y0528895*
X0873981Y0528915*
X0873951Y0528934*
X087392Y052895*
X0873888Y0528964*
X0873855Y0528976*
X0873822Y0528985*
X0873787Y0528993*
X0873753Y0528997*
X0873718Y0529*
X0873701Y0529*
X0840392Y0528106D02*
D01*
X0840423Y052798*
X0840464Y0527858*
X0840513Y0527738*
X084057Y0527622*
X0840635Y0527511*
X0840708Y0527404*
X0840788Y0527303*
X0840875Y0527207*
X0840968Y0527118*
X0841068Y0527036*
X0841173Y052696*
X0841283Y0526892*
X0841397Y0526832*
X0841515Y052678*
X0841637Y0526737*
X0841761Y0526702*
X0841888Y0526676*
X0842016Y0526658*
X0842144Y052665*
X0842274Y0526651*
X0842402Y052666*
X084253Y0526679*
X0842656Y0526706*
X084278Y0526743*
X0842901Y0526787*
X0843019Y0526841*
X0843133Y0526902*
X0843242Y0526971*
X0843346Y0527047*
X0843445Y0527131*
X0843537Y0527221*
X0843623Y0527317*
X0843702Y052742*
X0843774Y0527527*
X0843838Y0527639*
X0843894Y0527756*
X0843942Y0527876*
X0843981Y0527999*
X0843987Y0528023*
X0840392Y0528106D02*
D01*
X0840383Y0528139*
X0840372Y0528173*
X0840359Y0528205*
X0840343Y0528236*
X0840326Y0528266*
X0840306Y0528295*
X0840284Y0528323*
X0840261Y0528349*
X0840236Y0528373*
X0840209Y0528395*
X0840181Y0528415*
X0840151Y0528434*
X084012Y052845*
X0840088Y0528464*
X0840055Y0528476*
X0840022Y0528485*
X0839987Y0528493*
X0839953Y0528497*
X0839918Y05285*
X0839901Y05285*
X084145Y054D02*
D01*
X0841502Y0540001*
X0841554Y0540007*
X0841605Y0540016*
X0841656Y0540029*
X0841706Y0540045*
X0841755Y0540064*
X0841802Y0540087*
X0841847Y0540113*
X084189Y0540143*
X0841932Y0540175*
X084197Y054021*
X0842007Y0540248*
X0842041Y0540288*
X0842071Y054033*
X0842099Y0540375*
X0842124Y0540421*
X0842145Y0540469*
X0842163Y0540518*
X0842177Y0540568*
X0842188Y0540619*
X0842195Y0540671*
X0842199Y0540723*
X08422Y054075*
X084145Y054D02*
D01*
X0841397Y0539998*
X0841345Y0539992*
X0841294Y0539983*
X0841243Y053997*
X0841193Y0539954*
X0841144Y0539935*
X0841097Y0539912*
X0841052Y0539886*
X0841009Y0539856*
X0840967Y0539824*
X0840929Y0539789*
X0840892Y0539751*
X0840858Y0539711*
X0840828Y0539669*
X08408Y0539625*
X0840775Y0539578*
X0840754Y053953*
X0840736Y0539481*
X0840722Y0539431*
X0840711Y053938*
X0840704Y0539328*
X08407Y0539276*
Y0539223*
X0840704Y0539171*
X0840711Y0539119*
X0840722Y0539068*
X0840736Y0539018*
X0840754Y0538969*
X0840775Y0538921*
X08408Y0538875*
X0840828Y053883*
X0840858Y0538788*
X0840892Y0538748*
X0840929Y053871*
X0840967Y0538675*
X0841009Y0538643*
X0841052Y0538613*
X0841097Y0538587*
X0841144Y0538564*
X0841193Y0538545*
X0841243Y0538529*
X0841294Y0538516*
X0841345Y0538507*
X0841397Y0538501*
X084145Y05385*
X084185Y0537D02*
D01*
X0841902Y0537001*
X0841954Y0537007*
X0842005Y0537016*
X0842056Y0537029*
X0842106Y0537045*
X0842155Y0537064*
X0842202Y0537087*
X0842247Y0537113*
X084229Y0537143*
X0842332Y0537175*
X084237Y053721*
X0842407Y0537248*
X0842441Y0537288*
X0842471Y053733*
X0842499Y0537375*
X0842524Y0537421*
X0842545Y0537469*
X0842563Y0537518*
X0842577Y0537568*
X0842588Y0537619*
X0842595Y0537671*
X0842599Y0537723*
Y0537776*
X0842595Y0537828*
X0842588Y053788*
X0842577Y0537931*
X0842563Y0537981*
X0842545Y053803*
X0842524Y0538078*
X0842499Y0538125*
X0842471Y0538169*
X0842441Y0538211*
X0842407Y0538251*
X084237Y0538289*
X0842332Y0538324*
X084229Y0538356*
X0842247Y0538386*
X0842202Y0538412*
X0842155Y0538435*
X0842106Y0538454*
X0842056Y053847*
X0842005Y0538483*
X0841954Y0538492*
X0841902Y0538498*
X084185Y05385*
Y0537D02*
D01*
X0841797Y0536998*
X0841745Y0536992*
X0841694Y0536983*
X0841643Y053697*
X0841593Y0536954*
X0841544Y0536935*
X0841497Y0536912*
X0841452Y0536886*
X0841409Y0536856*
X0841367Y0536824*
X0841329Y0536789*
X0841292Y0536751*
X0841258Y0536711*
X0841228Y0536669*
X08412Y0536625*
X0841175Y0536578*
X0841154Y053653*
X0841136Y0536481*
X0841122Y0536431*
X0841111Y053638*
X0841104Y0536328*
X08411Y0536276*
Y0536223*
X0841104Y0536171*
X0841111Y0536119*
X0841122Y0536068*
X0841136Y0536018*
X0841154Y0535969*
X0841175Y0535921*
X08412Y0535875*
X0841228Y053583*
X0841258Y0535788*
X0841292Y0535748*
X0841329Y053571*
X0841367Y0535675*
X0841409Y0535643*
X0841452Y0535613*
X0841497Y0535587*
X0841544Y0535564*
X0841593Y0535545*
X0841643Y0535529*
X0841694Y0535516*
X0841745Y0535507*
X0841797Y0535501*
X084185Y05355*
Y0534D02*
D01*
X0841902Y0534001*
X0841954Y0534007*
X0842005Y0534016*
X0842056Y0534029*
X0842106Y0534045*
X0842155Y0534064*
X0842202Y0534087*
X0842247Y0534113*
X084229Y0534143*
X0842332Y0534175*
X084237Y053421*
X0842407Y0534248*
X0842441Y0534288*
X0842471Y053433*
X0842499Y0534375*
X0842524Y0534421*
X0842545Y0534469*
X0842563Y0534518*
X0842577Y0534568*
X0842588Y0534619*
X0842595Y0534671*
X0842599Y0534723*
Y0534776*
X0842595Y0534828*
X0842588Y053488*
X0842577Y0534931*
X0842563Y0534981*
X0842545Y053503*
X0842524Y0535078*
X0842499Y0535125*
X0842471Y0535169*
X0842441Y0535211*
X0842407Y0535251*
X084237Y0535289*
X0842332Y0535324*
X084229Y0535356*
X0842247Y0535386*
X0842202Y0535412*
X0842155Y0535435*
X0842106Y0535454*
X0842056Y053547*
X0842005Y0535483*
X0841954Y0535492*
X0841902Y0535498*
X084185Y05355*
X0841282Y0534D02*
D01*
X0841229Y0533998*
X0841177Y0533992*
X0841126Y0533983*
X0841075Y053397*
X0841025Y0533954*
X0840976Y0533935*
X0840929Y0533912*
X0840884Y0533886*
X0840841Y0533856*
X0840799Y0533824*
X0840761Y0533789*
X0840724Y0533751*
X084069Y0533711*
X084066Y0533669*
X0840632Y0533625*
X0840607Y0533578*
X0840586Y053353*
X0840568Y0533481*
X0840554Y0533431*
X0840543Y053338*
X0840536Y0533328*
X0840532Y0533276*
Y0533223*
X0840536Y0533171*
X0840543Y0533119*
X0840554Y0533068*
X0840568Y0533018*
X0840586Y0532969*
X0840607Y0532921*
X0840632Y0532875*
X084066Y053283*
X084069Y0532788*
X0840724Y0532748*
X0840761Y053271*
X0840799Y0532675*
X0840841Y0532643*
X0840884Y0532613*
X0840929Y0532587*
X0840976Y0532564*
X0841025Y0532545*
X0841075Y0532529*
X0841126Y0532516*
X0841177Y0532507*
X0841229Y0532501*
X0841282Y05325*
X08422Y053175D02*
D01*
X0842198Y0531802*
X0842192Y0531854*
X0842183Y0531905*
X084217Y0531956*
X0842154Y0532006*
X0842135Y0532055*
X0842112Y0532102*
X0842086Y0532147*
X0842056Y053219*
X0842024Y0532232*
X0841989Y053227*
X0841951Y0532307*
X0841911Y0532341*
X0841869Y0532371*
X0841825Y0532399*
X0841778Y0532424*
X084173Y0532445*
X0841681Y0532463*
X0841631Y0532477*
X084158Y0532488*
X0841528Y0532495*
X0841476Y0532499*
X084145Y05325*
X08665Y0589358D02*
D01*
X0866475Y0590055*
X0866402Y0590749*
X0866281Y0591437*
X0866112Y0592114*
X0865896Y0592778*
X0865635Y0593425*
X0865329Y0594052*
X086498Y0594657*
X086459Y0595235*
X086416Y0595785*
X0863693Y0596304*
X0863571Y0596429*
Y0573771D02*
D01*
X0864047Y0574281*
X0864486Y0574823*
X0864886Y0575395*
X0865246Y0575993*
X0865562Y0576615*
X0865835Y0577258*
X0866062Y0577918*
X0866243Y0578592*
X0866376Y0579277*
X0866461Y057997*
X0866498Y0580667*
X08665Y0580842*
X0846529Y0556729D02*
D01*
X0846052Y0556218*
X0845613Y0555676*
X0845213Y0555104*
X0844853Y0554506*
X0844537Y0553884*
X0844264Y0553241*
X0844037Y0552581*
X0843856Y0551907*
X0843723Y0551222*
X0843638Y0550529*
X0843601Y0549832*
X08436Y0549658*
Y0529883D02*
D01*
X0843601Y0529848*
X0843604Y0529813*
X084361Y0529779*
X0843619Y0529745*
X084363Y0529711*
X0843643Y0529679*
X0843658Y0529648*
X0843675Y0529618*
X0843695Y0529589*
X0843696Y0529589*
X0843987Y0528023D02*
D01*
X0844015Y0528148*
X0844035Y0528276*
X0844047Y0528405*
X0844049Y0528534*
X0844042Y0528663*
X0844026Y0528791*
X0844001Y0528918*
X0843968Y0529042*
X0843925Y0529165*
X0843875Y0529283*
X0843816Y0529398*
X0843749Y0529509*
X0843696Y0529589*
X0862371Y0574471D02*
D01*
X0862847Y0574981*
X0863286Y0575523*
X0863686Y0576095*
X0864046Y0576693*
X0864362Y0577315*
X0864635Y0577958*
X0864862Y0578618*
X0865043Y0579292*
X0865176Y0579977*
X0865261Y058067*
X0865298Y0581367*
X08653Y0581542*
X0845129Y0557229D02*
D01*
X0844652Y0556718*
X0844213Y0556176*
X0843813Y0555604*
X0843453Y0555006*
X0843137Y0554384*
X0842864Y0553741*
X0842637Y0553081*
X0842456Y0552407*
X0842323Y0551722*
X0842238Y0551029*
X0842201Y0550332*
X08422Y0550158*
X0868071Y0572571D02*
D01*
X0868547Y0573081*
X0868986Y0573623*
X0869386Y0574195*
X0869746Y0574793*
X0870062Y0575415*
X0870335Y0576058*
X0870562Y0576718*
X0870743Y0577392*
X0870876Y0578077*
X0870961Y057877*
X0870998Y0579467*
X0871Y0579642*
X0860869Y0530225D02*
D01*
X086087Y053019*
X0860873Y0530155*
X0860879Y0530121*
X0860888Y0530087*
X0860899Y0530053*
X0860912Y0530021*
X0860927Y052999*
X0860944Y052996*
X0860964Y0529931*
X0860971Y0529922*
X0863798Y0568298D02*
D01*
X0863321Y0567787*
X0862882Y0567245*
X0862482Y0566673*
X0862122Y0566075*
X0861806Y0565453*
X0861533Y056481*
X0861306Y056415*
X0861125Y0563476*
X0860992Y0562791*
X0860907Y0562098*
X086087Y0561401*
X0860869Y0561227*
Y0527556D02*
D01*
X0860952Y0527654*
X0861028Y0527758*
X0861097Y0527867*
X0861158Y0527981*
X0861211Y0528099*
X0861256Y052822*
X0861292Y0528344*
X086132Y052847*
X0861338Y0528598*
X0861348Y0528727*
X0861348Y0528856*
X086134Y0528984*
X0861323Y0529112*
X0861296Y0529239*
X0861261Y0529363*
X0861218Y0529485*
X0861166Y0529603*
X0861106Y0529717*
X0861038Y0529827*
X0860971Y0529922*
X0857677Y0528485D02*
D01*
X0857669Y0528519*
X085766Y0528552*
X0857648Y0528585*
X0857634Y0528617*
X0857618Y0528648*
X0857599Y0528678*
X0857579Y0528706*
X0857557Y0528733*
X0857532Y0528758*
X0857507Y0528782*
X0857479Y0528803*
X085745Y0528823*
X085742Y052884*
X0857389Y0528856*
X0857356Y0528869*
X0857323Y052888*
X0857289Y0528888*
X0857255Y0528895*
X085722Y0528898*
X0857185Y05289*
X0857181Y05289*
X0857677Y0528485D02*
D01*
X0857703Y0528358*
X0857738Y0528234*
X0857782Y0528112*
X0857834Y0527994*
X0857894Y052788*
X0857962Y052777*
X0858038Y0527666*
X085812Y0527566*
X085821Y0527473*
X0858305Y0527386*
X0858407Y0527307*
X0858514Y0527234*
X0858625Y0527169*
X0858741Y0527112*
X0858861Y0527063*
X0858983Y0527023*
X0859109Y0526991*
X0859236Y0526968*
X0859364Y0526954*
X0859493Y0526949*
X0859622Y0526954*
X0859751Y0526967*
X0859878Y0526989*
X0860003Y0527019*
X0860126Y0527059*
X0860246Y0527107*
X0860362Y0527163*
X0860474Y0527227*
X0860582Y0527299*
X0860684Y0527378*
X086078Y0527464*
X0860869Y0527556*
X087525Y05375D02*
D01*
X0875302Y0537501*
X0875354Y0537507*
X0875405Y0537516*
X0875456Y0537529*
X0875506Y0537545*
X0875555Y0537564*
X0875602Y0537587*
X0875647Y0537613*
X087569Y0537643*
X0875732Y0537675*
X087577Y053771*
X0875807Y0537748*
X0875841Y0537788*
X0875871Y053783*
X0875899Y0537875*
X0875924Y0537921*
X0875945Y0537969*
X0875963Y0538018*
X0875977Y0538068*
X0875988Y0538119*
X0875995Y0538171*
X0875999Y0538223*
X0876Y053825*
X0874628Y05375D02*
D01*
X0874575Y0537498*
X0874523Y0537492*
X0874472Y0537483*
X0874421Y053747*
X0874371Y0537454*
X0874322Y0537435*
X0874275Y0537412*
X087423Y0537386*
X0874187Y0537356*
X0874145Y0537324*
X0874107Y0537289*
X087407Y0537251*
X0874036Y0537211*
X0874006Y0537169*
X0873978Y0537125*
X0873953Y0537078*
X0873932Y053703*
X0873914Y0536981*
X08739Y0536931*
X0873889Y053688*
X0873882Y0536828*
X0873878Y0536776*
Y0536723*
X0873882Y0536671*
X0873889Y0536619*
X08739Y0536568*
X0873914Y0536518*
X0873932Y0536469*
X0873953Y0536421*
X0873978Y0536375*
X0874006Y053633*
X0874036Y0536288*
X087407Y0536248*
X0874107Y053621*
X0874145Y0536175*
X0874187Y0536143*
X087423Y0536113*
X0874275Y0536087*
X0874322Y0536064*
X0874371Y0536045*
X0874421Y0536029*
X0874472Y0536016*
X0874523Y0536007*
X0874575Y0536001*
X0874628Y0536*
X0875811Y05345D02*
D01*
X0875863Y0534501*
X0875915Y0534507*
X0875966Y0534516*
X0876017Y0534529*
X0876067Y0534545*
X0876116Y0534564*
X0876163Y0534587*
X0876208Y0534613*
X0876251Y0534643*
X0876293Y0534675*
X0876331Y053471*
X0876368Y0534748*
X0876402Y0534788*
X0876432Y053483*
X087646Y0534875*
X0876485Y0534921*
X0876506Y0534969*
X0876524Y0535018*
X0876538Y0535068*
X0876549Y0535119*
X0876556Y0535171*
X087656Y0535223*
Y0535276*
X0876556Y0535328*
X0876549Y053538*
X0876538Y0535431*
X0876524Y0535481*
X0876506Y053553*
X0876485Y0535578*
X087646Y0535625*
X0876432Y0535669*
X0876402Y0535711*
X0876368Y0535751*
X0876331Y0535789*
X0876293Y0535824*
X0876251Y0535856*
X0876208Y0535886*
X0876163Y0535912*
X0876116Y0535935*
X0876067Y0535954*
X0876017Y053597*
X0875966Y0535983*
X0875915Y0535992*
X0875863Y0535998*
X0875811Y0536*
X0874532Y05345D02*
D01*
X0874479Y0534498*
X0874427Y0534492*
X0874376Y0534483*
X0874325Y053447*
X0874275Y0534454*
X0874226Y0534435*
X0874179Y0534412*
X0874134Y0534386*
X0874091Y0534356*
X0874049Y0534324*
X0874011Y0534289*
X0873974Y0534251*
X087394Y0534211*
X087391Y0534169*
X0873882Y0534125*
X0873857Y0534078*
X0873836Y053403*
X0873818Y0533981*
X0873804Y0533931*
X0873793Y053388*
X0873786Y0533828*
X0873782Y0533776*
Y0533723*
X0873786Y0533671*
X0873793Y0533619*
X0873804Y0533568*
X0873818Y0533518*
X0873836Y0533469*
X0873857Y0533421*
X0873882Y0533375*
X087391Y053333*
X087394Y0533288*
X0873974Y0533248*
X0874011Y053321*
X0874049Y0533175*
X0874091Y0533143*
X0874134Y0533113*
X0874179Y0533087*
X0874226Y0533064*
X0874275Y0533045*
X0874325Y0533029*
X0874376Y0533016*
X0874427Y0533007*
X0874479Y0533001*
X0874532Y0533*
X0876Y053225D02*
D01*
X0875998Y0532302*
X0875992Y0532354*
X0875983Y0532405*
X087597Y0532456*
X0875954Y0532506*
X0875935Y0532555*
X0875912Y0532602*
X0875886Y0532647*
X0875856Y053269*
X0875824Y0532732*
X0875789Y053277*
X0875751Y0532807*
X0875711Y0532841*
X0875669Y0532871*
X0875625Y0532899*
X0875578Y0532924*
X087553Y0532945*
X0875481Y0532963*
X0875431Y0532977*
X087538Y0532988*
X0875328Y0532995*
X0875276Y0532999*
X087525Y0533*
X088049Y057749D02*
D01*
X0880013Y0576979*
X0879574Y0576437*
X0879174Y0575865*
X0878814Y0575267*
X0878498Y0574645*
X0878225Y0574002*
X0877998Y0573342*
X0877817Y0572668*
X0877684Y0571983*
X0877599Y057129*
X0877562Y0570593*
X0877561Y0570419*
Y0530129D02*
D01*
X0877562Y0530094*
X0877565Y0530059*
X0877571Y0530025*
X087758Y0529991*
X0877591Y0529957*
X0877604Y0529925*
X0877619Y0529894*
X0877622Y0529889*
X0877561Y0528007D02*
D01*
X0877626Y0528118*
X0877684Y0528233*
X0877733Y0528353*
X0877774Y0528475*
X0877806Y05286*
X0877829Y0528727*
X0877844Y0528856*
X087785Y0528985*
X0877846Y0529114*
X0877834Y0529242*
X0877812Y052937*
X0877782Y0529495*
X0877743Y0529618*
X0877696Y0529738*
X087764Y0529855*
X0877622Y0529889*
X08783Y0579D02*
D01*
X0877926Y0578599*
X0877581Y0578173*
X0877266Y0577724*
X0876984Y0577254*
X0876735Y0576765*
X0876521Y0576261*
X0876343Y0575743*
X0876201Y0575213*
X0876096Y0574675*
X0876029Y0574131*
X0876001Y0573584*
X0876Y0573447*
X08922Y053235D02*
D01*
X0892198Y0532402*
X0892192Y0532454*
X0892183Y0532505*
X089217Y0532556*
X0892154Y0532606*
X0892135Y0532655*
X0892112Y0532702*
X0892086Y0532747*
X0892056Y053279*
X0892024Y0532832*
X0891989Y053287*
X0891951Y0532907*
X0891911Y0532941*
X0891869Y0532971*
X0891825Y0532999*
X0891778Y0533024*
X089173Y0533045*
X0891681Y0533063*
X0891631Y0533077*
X089158Y0533088*
X0891528Y0533095*
X0891476Y0533099*
X089145Y05331*
X0891437Y05346D02*
D01*
X0891384Y0534598*
X0891332Y0534592*
X0891281Y0534583*
X089123Y053457*
X089118Y0534554*
X0891131Y0534535*
X0891084Y0534512*
X0891039Y0534486*
X0890996Y0534456*
X0890954Y0534424*
X0890916Y0534389*
X0890879Y0534351*
X0890845Y0534311*
X0890815Y0534269*
X0890787Y0534225*
X0890762Y0534178*
X0890741Y053413*
X0890723Y0534081*
X0890709Y0534031*
X0890698Y053398*
X0890691Y0533928*
X0890687Y0533876*
Y0533823*
X0890691Y0533771*
X0890698Y0533719*
X0890709Y0533668*
X0890723Y0533618*
X0890741Y0533569*
X0890762Y0533521*
X0890787Y0533475*
X0890815Y053343*
X0890845Y0533388*
X0890879Y0533348*
X0890916Y053331*
X0890954Y0533275*
X0890996Y0533243*
X0891039Y0533213*
X0891084Y0533187*
X0891131Y0533164*
X089118Y0533145*
X089123Y0533129*
X0891281Y0533116*
X0891332Y0533107*
X0891384Y0533101*
X0891437Y05331*
X089245Y05346D02*
D01*
X0892502Y0534601*
X0892554Y0534607*
X0892605Y0534616*
X0892656Y0534629*
X0892706Y0534645*
X0892755Y0534664*
X0892802Y0534687*
X0892847Y0534713*
X089289Y0534743*
X0892932Y0534775*
X089297Y053481*
X0893007Y0534848*
X0893041Y0534888*
X0893071Y053493*
X0893099Y0534975*
X0893124Y0535021*
X0893145Y0535069*
X0893163Y0535118*
X0893177Y0535168*
X0893188Y0535219*
X0893195Y0535271*
X0893199Y0535323*
Y0535376*
X0893195Y0535428*
X0893188Y053548*
X0893177Y0535531*
X0893163Y0535581*
X0893145Y053563*
X0893124Y0535678*
X0893099Y0535725*
X0893071Y0535769*
X0893041Y0535811*
X0893007Y0535851*
X089297Y0535889*
X0892932Y0535924*
X089289Y0535956*
X0892847Y0535986*
X0892802Y0536012*
X0892755Y0536035*
X0892706Y0536054*
X0892656Y053607*
X0892605Y0536083*
X0892554Y0536092*
X0892502Y0536098*
X089245Y05361*
X0891222Y05376D02*
D01*
X0891169Y0537598*
X0891117Y0537592*
X0891066Y0537583*
X0891015Y053757*
X0890965Y0537554*
X0890916Y0537535*
X0890869Y0537512*
X0890824Y0537486*
X0890781Y0537456*
X0890739Y0537424*
X0890701Y0537389*
X0890664Y0537351*
X089063Y0537311*
X08906Y0537269*
X0890572Y0537225*
X0890547Y0537178*
X0890526Y053713*
X0890508Y0537081*
X0890494Y0537031*
X0890483Y053698*
X0890476Y0536928*
X0890472Y0536876*
Y0536823*
X0890476Y0536771*
X0890483Y0536719*
X0890494Y0536668*
X0890508Y0536618*
X0890526Y0536569*
X0890547Y0536521*
X0890572Y0536475*
X08906Y053643*
X089063Y0536388*
X0890664Y0536348*
X0890701Y053631*
X0890739Y0536275*
X0890781Y0536243*
X0890824Y0536213*
X0890869Y0536187*
X0890916Y0536164*
X0890965Y0536145*
X0891015Y0536129*
X0891066Y0536116*
X0891117Y0536107*
X0891169Y0536101*
X0891222Y05361*
X089145Y05376D02*
D01*
X0891502Y0537601*
X0891554Y0537607*
X0891605Y0537616*
X0891656Y0537629*
X0891706Y0537645*
X0891755Y0537664*
X0891802Y0537687*
X0891847Y0537713*
X089189Y0537743*
X0891932Y0537775*
X089197Y053781*
X0892007Y0537848*
X0892041Y0537888*
X0892071Y053793*
X0892099Y0537975*
X0892124Y0538021*
X0892145Y0538069*
X0892163Y0538118*
X0892177Y0538168*
X0892188Y0538219*
X0892195Y0538271*
X0892199Y0538323*
X08922Y053835*
X0889277Y0587923D02*
D01*
X0889275Y0587924*
X0889274Y0587925*
X0889273Y0587926*
X0889272Y0587927*
X0889271Y0587929*
X08922Y0580858D02*
D01*
X0892175Y0581555*
X0892102Y0582249*
X0891981Y0582937*
X0891812Y0583614*
X0891596Y0584278*
X0891335Y0584925*
X0891029Y0585552*
X089068Y0586157*
X089029Y0586735*
X088986Y0587285*
X0889393Y0587804*
X0889277Y0587923*
X0886444Y0590757D02*
D01*
X0886209Y0590975*
X0885961Y0591176*
X0885698Y059136*
X0885424Y0591525*
X0885139Y059167*
X0884844Y0591795*
X0884541Y0591899*
X0884232Y0591982*
X0883918Y0592043*
X08836Y0592082*
X0883281Y0592099*
X08832Y05921*
X08943Y0582282D02*
D01*
X0894277Y0582925*
X089421Y0583564*
X0894098Y0584198*
X0893942Y0584822*
X0893744Y0585434*
X0893503Y0586031*
X0893221Y0586609*
X0892899Y0587166*
X0892539Y05877*
X0892143Y0588207*
X0891712Y0588685*
X08916Y05888*
X0893756Y05277D02*
D01*
X0893844Y0527794*
X0893925Y0527895*
X0894Y0528001*
X0894067Y0528112*
X0894125Y0528228*
X0894176Y0528347*
X0894218Y052847*
X0894252Y0528595*
X0894277Y0528722*
X0894292Y0528851*
X0894299Y052898*
X08943Y0529012*
X0877884Y0596729D02*
D01*
X0878394Y0596252*
X0878936Y0595813*
X0879508Y0595413*
X0880106Y0595053*
X0880728Y0594737*
X0881371Y0594464*
X0882031Y0594237*
X0882705Y0594056*
X088339Y0593923*
X0884083Y0593838*
X088478Y0593801*
X0884955Y05938*
X0887731Y0592669D02*
D01*
X0887533Y0592852*
X0887324Y0593022*
X0887103Y0593177*
X0886872Y0593315*
X0886632Y0593438*
X0886384Y0593543*
X0886129Y0593631*
X0885868Y0593701*
X0885604Y0593752*
X0885336Y0593785*
X0885067Y0593799*
X0885Y05938*
X0873525Y0599177D02*
D01*
X0873535Y059889*
X0873564Y0598604*
X0873614Y0598322*
X0873684Y0598044*
X0873772Y0597771*
X087388Y0597505*
X0874006Y0597247*
X0874149Y0596999*
X0874309Y0596761*
X0874486Y0596535*
X0874678Y0596321*
X0874729Y0596271*
X0875971Y0595029D02*
D01*
X0876481Y0594552*
X0877023Y0594113*
X0877595Y0593713*
X0878193Y0593353*
X0878815Y0593037*
X0879458Y0592764*
X0880118Y0592537*
X0880792Y0592356*
X0881477Y0592223*
X088217Y0592138*
X0882867Y0592101*
X0883042Y05921*
X08727Y05947D02*
D01*
X0872423Y0594403*
X0872168Y0594088*
X0871936Y0593757*
X0871727Y0593409*
X0871543Y0593048*
X0871385Y0592675*
X0871253Y0592292*
X0871148Y0591901*
X0871071Y0591503*
X0871022Y0591101*
X0871Y0590697*
X0871Y0590596*
X08422Y05285D02*
Y053175D01*
X08398Y05285D02*
X0839901D01*
X08595Y05469D02*
Y0561758D01*
X0862429Y0568829D02*
X08676Y0574D01*
X08694Y0578346D02*
Y05952D01*
X08595Y053805D02*
Y05469D01*
X0858162Y05373D02*
X085875D01*
X0858162Y05358D02*
X0859119D01*
X0858062Y05343D02*
X0859119D01*
X0858062Y05328D02*
X085875D01*
X08595Y05288D02*
Y053205D01*
X08622Y05978D02*
X0863571Y0596429D01*
X0876532Y0598081D02*
X0877884Y0596729D01*
X0890392Y0528306D02*
D01*
X08898Y05287D02*
X0889901D01*
X0874192Y0528606D02*
D01*
X0873701Y0529D02*
D01*
X08736D02*
X0873701D01*
X0840392Y0528106D02*
D01*
X0839901Y05285D02*
D01*
X08422Y054075D02*
Y0550158D01*
X084145Y054D02*
D01*
Y05385D02*
X084185D01*
Y0537D02*
D01*
Y05355D02*
D01*
X0841282Y0534D02*
X084185D01*
X0841282Y05325D02*
X084145D01*
X08665Y0580842D02*
Y0589358D01*
X0846529Y0556729D02*
X0863571Y0573771D01*
X08436Y05401D02*
Y0549658D01*
X0843696Y0529589D02*
D01*
X08436Y0529883D02*
Y05401D01*
X08653Y0581542D02*
Y0587258D01*
X0845129Y0557229D02*
X0862371Y0574471D01*
X08588Y05979D02*
X0862371Y0594329D01*
X0860971Y0529922D02*
D01*
X0863798Y0568298D02*
X0868071Y0572571D01*
X0860869Y0530225D02*
Y0561227D01*
X0857181Y05289D02*
D01*
X08566D02*
X0857181D01*
X0857677Y0528485D02*
D01*
X0871Y0579642D02*
Y0590596D01*
X0876Y053825D02*
Y05409D01*
X0874628Y05375D02*
X087525D01*
X0874628Y0536D02*
X0875811D01*
X0874532Y05345D02*
X0875811D01*
X0874532Y0533D02*
X087525D01*
X0876Y0529D02*
Y053225D01*
Y05409D02*
Y0573447D01*
X088049Y057749D02*
X08822Y05792D01*
X0877561Y0530129D02*
Y0570419D01*
X0877622Y0529889D02*
D01*
X08922Y05304D02*
Y053235D01*
X0891437Y05331D02*
X089145D01*
X0891437Y05346D02*
X089245D01*
X0891222Y05361D02*
X089245D01*
X0891222Y05376D02*
X089145D01*
X08922Y053835D02*
Y05401D01*
Y05287D02*
Y05304D01*
Y05401D02*
Y0580858D01*
X0886444Y0590757D02*
X0889271Y0587929D01*
X0887731Y0592669D02*
X08916Y05888D01*
X08943Y0529012D02*
Y0582282D01*
X0884955Y05938D02*
X0885D01*
X0874729Y0596271D02*
X0875971Y0595029D01*
X0883042Y05921D02*
X08832D01*
G54D147*
X0806496Y093015D02*
X0810646Y0926D01*
X08534D02*
X08561Y09287D01*
X0739404Y092185D02*
X0749673D01*
X0757973Y093015*
X0810646Y0926D02*
X08534D01*
X0735254D02*
X0739404Y092185D01*
X0757973Y093015D02*
X0806496D01*
X07285Y0926D02*
X0735254D01*
X0784Y08705D02*
X12285D01*
G54D148*
X09265Y0861D02*
X1066D01*
G54D155*
X1028878Y0759928D03*
X1017067D03*
G54D162*
X0803Y09156D03*
G54D165*
X08422Y05285D03*
X08398D03*
X0876Y0529D03*
X08736D03*
X08898Y05287D03*
X08595Y05288D03*
X08566Y05289D03*
X08922Y05287D03*
X1125716Y0909284D03*
X0996Y06556D03*
X0781294Y0667794D03*
X0787009Y0681574D03*
X08321Y07219D03*
X11568Y07218D03*
X08685Y06485D03*
X10055Y06515D03*
X08375Y06945D03*
X09795Y06844D03*
X12325Y0827D03*
X09735Y08265D03*
X0849Y0724D03*
X11625D03*
X08617Y06774D03*
X10055Y068D03*
X12295Y08125D03*
X0993D03*
X08716Y08164D03*
X09048Y08159D03*
X09188Y07974D03*
X08414Y08127D03*
X08485Y07665D03*
X10125Y06755D03*
X08595Y06738D03*
X08694Y05952D03*
X0829Y0692D03*
X09545Y06895D03*
X08485Y077D03*
X0857Y06794D03*
X09935Y0682D03*
X0825Y08265D03*
X09365Y08277D03*
X08566Y07416D03*
X1003Y0741D03*
X0971Y0677D03*
X0854Y06759D03*
X09268Y06809D03*
X09265Y0861D03*
X1066D03*
X1227257Y0823D03*
X09797Y08239D03*
X08561Y09287D03*
X0745Y08151D03*
X07431Y08561D03*
X07576Y09129D03*
X07894Y09022D03*
X08235Y09021D03*
X08812Y07605D03*
X09614Y07591D03*
X0953302Y0832298D03*
X09644Y08297D03*
X09385Y08451D03*
X09427Y08461D03*
X08425Y0855D03*
X07884Y06697D03*
X0879Y0862D03*
X0958Y06715D03*
X08469Y05941D03*
X08622Y05978D03*
X08783Y0579D03*
X084Y07318D03*
X07556Y06323D03*
X08794Y07311D03*
X08822Y05792D03*
X08727Y05947D03*
X09395Y0636726D03*
X0873525Y0599177D03*
X08949Y07625D03*
X0937Y0639D03*
X08939Y0746D03*
X08588Y05979D03*
X0937Y0634D03*
X07782Y06301D03*
X0939744Y0641526D03*
X08832Y07267D03*
X09221Y08239D03*
X09243Y08297D03*
X08197Y06302D03*
X08196Y08204D03*
X08495Y08086D03*
X08493Y0632D03*
X0841Y08198D03*
X08581Y08292D03*
X08582Y08204D03*
X08516Y07467D03*
X09333Y07267D03*
X09489Y07345D03*
X0841935Y07625D03*
X06995Y0591D03*
X08437Y06441D03*
X06999Y06434D03*
X084Y06971D03*
X07Y0696D03*
X07011Y07485D03*
X08634Y0662D03*
X08657Y06644D03*
X0876532Y0598081D03*
X07875Y08605D03*
X07745Y08665D03*
X09415Y0864D03*
X0754Y08625D03*
X0923Y086D03*
X07565D03*
X08074Y064156D03*
X0805Y0639D03*
X08019Y063656D03*
X07285Y0926D03*
X07995Y0634D03*
X08225Y0851D03*
X0952Y08485D03*
X0867Y08665D03*
X0898354Y08755D03*
X0969D03*
X09005Y08835D03*
X0969Y0884D03*
X08885Y06565D03*
X0891Y0654D03*
X09985Y06555D03*
X08265Y0651D03*
X10025Y0655D03*
X0871Y06595D03*
X1017Y06605D03*
X1014146Y0662756D03*
X10125Y06655D03*
X09715Y06679D03*
X1229957Y08203D03*
X1233Y08155D03*
X1074487Y0911987D03*
X0777Y0916D03*
X09495Y0909D03*
X09845Y08155D03*
X0982Y0818D03*
X0979Y08205D03*
X1243Y08195D03*
X1234491Y0833508D03*
X12435Y08295D03*
X09293Y08348D03*
X124Y08375D03*
X1243773Y084D03*
X1247Y0843D03*
X125Y0846D03*
X0946D03*
X0784Y08705D03*
X12285D03*
M02*